(kicad_pcb
	(version 20260206)
	(generator "pcbnew")
	(generator_version "10.0")
	(general
		(thickness 1.6)
		(legacy_teardrops no)
	)
	(paper "A4")
	(title_block
		(title "01162023_DA0F0TEBIF0_F0T_Expander_BD_F_brd_V02_OCP.brd")
		(comment 1 "Grand Teton / footprints 6627-6632 of 9728")
	)
	(layers
		(0 "F.Cu" signal "TOP")
		(4 "In1.Cu" signal "GND")
		(6 "In2.Cu" signal "VCC")
		(8 "In3.Cu" signal "VCC1")
		(10 "In4.Cu" signal "GND1")
		(12 "In5.Cu" signal "IN1")
		(14 "In6.Cu" signal "GND2")
		(16 "In7.Cu" signal "IN2")
		(18 "In8.Cu" signal "GND3")
		(20 "In9.Cu" signal "IN3")
		(22 "In10.Cu" signal "GND4")
		(24 "In11.Cu" signal "IN4")
		(26 "In12.Cu" signal "GND5")
		(28 "In13.Cu" signal "IN5")
		(30 "In14.Cu" signal "GND6")
		(32 "In15.Cu" signal "IN6")
		(34 "In16.Cu" signal "GND7")
		(2 "B.Cu" signal "BOTTOM")
		(9 "F.Adhes" user "F.Adhesive")
		(11 "B.Adhes" user "B.Adhesive")
		(13 "F.Paste" user "Package Geometry/Pastemask Top")
		(15 "B.Paste" user "Package Geometry/Pastemask Bottom")
		(5 "F.SilkS" user "Ref Des/Silkscreen Top")
		(7 "B.SilkS" user "Ref Des/Silkscreen Bottom")
		(1 "F.Mask" user "Board Geometry/Soldermask Top")
		(3 "B.Mask" user "Board Geometry/Soldermask Bottom")
		(17 "Dwgs.User" user "User.Drawings")
		(19 "Cmts.User" user "User.Comments")
		(21 "Eco1.User" user "User.Eco1")
		(23 "Eco2.User" user "User.Eco2")
		(25 "Edge.Cuts" user "Board Geometry/Outline")
		(27 "Margin" user)
		(31 "F.CrtYd" user "Package Geometry/Place Bound Top")
		(29 "B.CrtYd" user "Package Geometry/Place Bound Bottom")
		(35 "F.Fab" user "Ref Des/Assembly Top")
		(33 "B.Fab" user "Ref Des/Assembly Bottom")
	)
	(footprint ""
		(layer "F.Cu")
		(at 352.67392 -27.006296 -90)
		(property "Reference" "PC960"
			(at 0 0 270)
			(layer "F.SilkS")
			(hide yes)
			(effects
				(font
					(size 1.27 1.27)
				)
			)
		)
		(property "Value" ""
			(at 0 0 270)
			(layer "F.Fab")
			(effects
				(font
					(size 1.27 1.27)
				)
			)
		)
		(duplicate_pad_numbers_are_jumpers no)
		(fp_line
			(start -0.7874 0.4064)
			(end -0.7874 -0.4064)
			(stroke
				(width 0.1524)
				(type default)
			)
			(layer "F.SilkS")
		)
		(fp_line
			(start 0.7874 0.4064)
			(end -0.7874 0.4064)
			(stroke
				(width 0.1524)
				(type default)
			)
			(layer "F.SilkS")
		)
		(fp_line
			(start -0.7874 -0.4064)
			(end 0.7874 -0.4064)
			(stroke
				(width 0.1524)
				(type default)
			)
			(layer "F.SilkS")
		)
		(fp_line
			(start 0.7874 -0.4064)
			(end 0.7874 0.4064)
			(stroke
				(width 0.1524)
				(type default)
			)
			(layer "F.SilkS")
		)
		(fp_line
			(start -0.67945 0.3048)
			(end -0.67945 -0.305054)
			(stroke
				(width 0.1)
				(type default)
			)
			(layer "F.Fab")
		)
		(fp_line
			(start -0.12065 0.3048)
			(end -0.67945 0.3048)
			(stroke
				(width 0.1)
				(type default)
			)
			(layer "F.Fab")
		)
		(fp_line
			(start 0.120396 0.3048)
			(end 0.120396 0.2794)
			(stroke
				(width 0.1)
				(type default)
			)
			(layer "F.Fab")
		)
		(fp_line
			(start 0.67945 0.3048)
			(end 0.120396 0.3048)
			(stroke
				(width 0.1)
				(type default)
			)
			(layer "F.Fab")
		)
		(fp_line
			(start -0.12065 0.2794)
			(end -0.12065 0.3048)
			(stroke
				(width 0.1)
				(type default)
			)
			(layer "F.Fab")
		)
		(fp_line
			(start 0.120396 0.2794)
			(end -0.12065 0.2794)
			(stroke
				(width 0.1)
				(type default)
			)
			(layer "F.Fab")
		)
		(fp_line
			(start -0.12065 -0.2794)
			(end 0.12065 -0.2794)
			(stroke
				(width 0.1)
				(type default)
			)
			(layer "F.Fab")
		)
		(fp_line
			(start 0.12065 -0.2794)
			(end 0.12065 -0.3048)
			(stroke
				(width 0.1)
				(type default)
			)
			(layer "F.Fab")
		)
		(fp_line
			(start 0.12065 -0.3048)
			(end 0.67945 -0.3048)
			(stroke
				(width 0.1)
				(type default)
			)
			(layer "F.Fab")
		)
		(fp_line
			(start 0.67945 -0.3048)
			(end 0.67945 0.3048)
			(stroke
				(width 0.1)
				(type default)
			)
			(layer "F.Fab")
		)
		(fp_line
			(start -0.67945 -0.305054)
			(end -0.12065 -0.305054)
			(stroke
				(width 0.1)
				(type default)
			)
			(layer "F.Fab")
		)
		(fp_line
			(start -0.12065 -0.305054)
			(end -0.12065 -0.2794)
			(stroke
				(width 0.1)
				(type default)
			)
			(layer "F.Fab")
		)
		(pad "1" smd circle
			(at -0.40005 0 270)
			(size 0 0)
			(layers "F.Cu" "F.Mask" "F.Paste")
			(net "P3V3_SSD12_CO_MODE")
		)
		(pad "2" smd circle
			(at 0.40005 0 270)
			(size 0 0)
			(layers "F.Cu" "F.Mask" "F.Paste")
			(net "GND")
		)
	)
	(footprint ""
		(layer "F.Cu")
		(at 405.594058 -35.264852)
		(property "Reference" "R5711"
			(at 0 0 0)
			(layer "F.SilkS")
			(hide yes)
			(effects
				(font
					(size 1.27 1.27)
				)
			)
		)
		(property "Value" ""
			(at 0 0 0)
			(layer "F.Fab")
			(effects
				(font
					(size 1.27 1.27)
				)
			)
		)
		(duplicate_pad_numbers_are_jumpers no)
		(fp_line
			(start -0.7874 -0.4064)
			(end 0.7874 -0.4064)
			(stroke
				(width 0.1524)
				(type default)
			)
			(layer "F.SilkS")
		)
		(fp_line
			(start -0.7874 0.4064)
			(end -0.7874 -0.4064)
			(stroke
				(width 0.1524)
				(type default)
			)
			(layer "F.SilkS")
		)
		(fp_line
			(start 0.7874 -0.4064)
			(end 0.7874 0.4064)
			(stroke
				(width 0.1524)
				(type default)
			)
			(layer "F.SilkS")
		)
		(fp_line
			(start 0.7874 0.4064)
			(end -0.7874 0.4064)
			(stroke
				(width 0.1524)
				(type default)
			)
			(layer "F.SilkS")
		)
		(fp_line
			(start -0.67945 -0.305054)
			(end -0.12065 -0.305054)
			(stroke
				(width 0.1)
				(type default)
			)
			(layer "F.Fab")
		)
		(fp_line
			(start -0.67945 0.3048)
			(end -0.67945 -0.305054)
			(stroke
				(width 0.1)
				(type default)
			)
			(layer "F.Fab")
		)
		(fp_line
			(start -0.12065 -0.305054)
			(end -0.12065 -0.2794)
			(stroke
				(width 0.1)
				(type default)
			)
			(layer "F.Fab")
		)
		(fp_line
			(start -0.12065 -0.2794)
			(end 0.12065 -0.2794)
			(stroke
				(width 0.1)
				(type default)
			)
			(layer "F.Fab")
		)
		(fp_line
			(start -0.12065 0.2794)
			(end -0.12065 0.3048)
			(stroke
				(width 0.1)
				(type default)
			)
			(layer "F.Fab")
		)
		(fp_line
			(start -0.12065 0.3048)
			(end -0.67945 0.3048)
			(stroke
				(width 0.1)
				(type default)
			)
			(layer "F.Fab")
		)
		(fp_line
			(start 0.120396 0.2794)
			(end -0.12065 0.2794)
			(stroke
				(width 0.1)
				(type default)
			)
			(layer "F.Fab")
		)
		(fp_line
			(start 0.120396 0.3048)
			(end 0.120396 0.2794)
			(stroke
				(width 0.1)
				(type default)
			)
			(layer "F.Fab")
		)
		(fp_line
			(start 0.12065 -0.3048)
			(end 0.67945 -0.3048)
			(stroke
				(width 0.1)
				(type default)
			)
			(layer "F.Fab")
		)
		(fp_line
			(start 0.12065 -0.2794)
			(end 0.12065 -0.3048)
			(stroke
				(width 0.1)
				(type default)
			)
			(layer "F.Fab")
		)
		(fp_line
			(start 0.67945 -0.3048)
			(end 0.67945 0.3048)
			(stroke
				(width 0.1)
				(type default)
			)
			(layer "F.Fab")
		)
		(fp_line
			(start 0.67945 0.3048)
			(end 0.120396 0.3048)
			(stroke
				(width 0.1)
				(type default)
			)
			(layer "F.Fab")
		)
		(pad "1" smd circle
			(at -0.40005 0)
			(size 0 0)
			(layers "F.Cu" "F.Mask" "F.Paste")
			(net "RST_SMB_SSD14_ISO_N")
		)
		(pad "2" smd circle
			(at 0.40005 0)
			(size 0 0)
			(layers "F.Cu" "F.Mask" "F.Paste")
			(net "GND")
		)
	)
	(footprint ""
		(layer "F.Cu")
		(at 396.327884 -35.876738)
		(property "Reference" "R6118"
			(at 0 0 0)
			(layer "F.SilkS")
			(hide yes)
			(effects
				(font
					(size 1.27 1.27)
				)
			)
		)
		(property "Value" ""
			(at 0 0 0)
			(layer "F.Fab")
			(effects
				(font
					(size 1.27 1.27)
				)
			)
		)
		(duplicate_pad_numbers_are_jumpers no)
		(fp_line
			(start -0.7874 -0.4064)
			(end 0.7874 -0.4064)
			(stroke
				(width 0.1524)
				(type default)
			)
			(layer "F.SilkS")
		)
		(fp_line
			(start -0.7874 0.4064)
			(end -0.7874 -0.4064)
			(stroke
				(width 0.1524)
				(type default)
			)
			(layer "F.SilkS")
		)
		(fp_line
			(start 0.7874 -0.4064)
			(end 0.7874 0.4064)
			(stroke
				(width 0.1524)
				(type default)
			)
			(layer "F.SilkS")
		)
		(fp_line
			(start 0.7874 0.4064)
			(end -0.7874 0.4064)
			(stroke
				(width 0.1524)
				(type default)
			)
			(layer "F.SilkS")
		)
		(fp_line
			(start -0.67945 -0.305054)
			(end -0.12065 -0.305054)
			(stroke
				(width 0.1)
				(type default)
			)
			(layer "F.Fab")
		)
		(fp_line
			(start -0.67945 0.3048)
			(end -0.67945 -0.305054)
			(stroke
				(width 0.1)
				(type default)
			)
			(layer "F.Fab")
		)
		(fp_line
			(start -0.12065 -0.305054)
			(end -0.12065 -0.2794)
			(stroke
				(width 0.1)
				(type default)
			)
			(layer "F.Fab")
		)
		(fp_line
			(start -0.12065 -0.2794)
			(end 0.12065 -0.2794)
			(stroke
				(width 0.1)
				(type default)
			)
			(layer "F.Fab")
		)
		(fp_line
			(start -0.12065 0.2794)
			(end -0.12065 0.3048)
			(stroke
				(width 0.1)
				(type default)
			)
			(layer "F.Fab")
		)
		(fp_line
			(start -0.12065 0.3048)
			(end -0.67945 0.3048)
			(stroke
				(width 0.1)
				(type default)
			)
			(layer "F.Fab")
		)
		(fp_line
			(start 0.120396 0.2794)
			(end -0.12065 0.2794)
			(stroke
				(width 0.1)
				(type default)
			)
			(layer "F.Fab")
		)
		(fp_line
			(start 0.120396 0.3048)
			(end 0.120396 0.2794)
			(stroke
				(width 0.1)
				(type default)
			)
			(layer "F.Fab")
		)
		(fp_line
			(start 0.12065 -0.3048)
			(end 0.67945 -0.3048)
			(stroke
				(width 0.1)
				(type default)
			)
			(layer "F.Fab")
		)
		(fp_line
			(start 0.12065 -0.2794)
			(end 0.12065 -0.3048)
			(stroke
				(width 0.1)
				(type default)
			)
			(layer "F.Fab")
		)
		(fp_line
			(start 0.67945 -0.3048)
			(end 0.67945 0.3048)
			(stroke
				(width 0.1)
				(type default)
			)
			(layer "F.Fab")
		)
		(fp_line
			(start 0.67945 0.3048)
			(end 0.120396 0.3048)
			(stroke
				(width 0.1)
				(type default)
			)
			(layer "F.Fab")
		)
		(pad "1" smd circle
			(at -0.40005 0)
			(size 0 0)
			(layers "F.Cu" "F.Mask" "F.Paste")
			(net "PWRGD_P3V3_SSD14_D")
		)
		(pad "2" smd circle
			(at 0.40005 0)
			(size 0 0)
			(layers "F.Cu" "F.Mask" "F.Paste")
			(net "PWRGD_P3V3_SSD14_R")
		)
	)
	(footprint ""
		(layer "F.Cu")
		(at 171.487592 -343.952322 90)
		(property "Reference" "C2520"
			(at 0 0 90)
			(layer "F.SilkS")
			(hide yes)
			(effects
				(font
					(size 1.27 1.27)
				)
			)
		)
		(property "Value" ""
			(at 0 0 90)
			(layer "F.Fab")
			(effects
				(font
					(size 1.27 1.27)
				)
			)
		)
		(duplicate_pad_numbers_are_jumpers no)
		(fp_line
			(start 0.299974 -0.150114)
			(end 0.299974 0.150114)
			(stroke
				(width 0.1)
				(type default)
			)
			(layer "F.Fab")
		)
		(fp_line
			(start -0.299974 -0.150114)
			(end 0.299974 -0.150114)
			(stroke
				(width 0.1)
				(type default)
			)
			(layer "F.Fab")
		)
		(fp_line
			(start 0.299974 0.150114)
			(end -0.299974 0.150114)
			(stroke
				(width 0.1)
				(type default)
			)
			(layer "F.Fab")
		)
		(fp_line
			(start -0.299974 0.150114)
			(end -0.299974 -0.150114)
			(stroke
				(width 0.1)
				(type default)
			)
			(layer "F.Fab")
		)
		(pad "1" smd rect
			(at -0.2667 0 90)
			(size 0.3048 0.381)
			(layers "F.Cu" "F.Mask" "F.Paste")
			(net "P5E_PEX1_STN4_TX_DP<75>")
		)
		(pad "2" smd rect
			(at 0.2667 0 90)
			(size 0.3048 0.381)
			(layers "F.Cu" "F.Mask" "F.Paste")
			(net "P5E_PEX1_STN4_TX_C_DP<75>")
		)
	)
	(footprint ""
		(layer "F.Cu")
		(at 321.84975 -270.89989)
		(property "Reference" "H86"
			(at -2.438908 -8.862568 0)
			(unlocked yes)
			(layer "F.SilkS")
			(effects
				(font
					(size 0.7874 0.5842)
					(thickness 0.1524)
				)
				(justify left)
			)
		)
		(property "Value" ""
			(at 0 0 0)
			(layer "F.Fab")
			(effects
				(font
					(size 1.27 1.27)
				)
			)
		)
		(duplicate_pad_numbers_are_jumpers no)
		(fp_arc
			(start -5.701792 -5.611368)
			(mid 3.031933 -7.403178)
			(end 7.999984 0)
			(stroke
				(width 0.1524)
				(type default)
			)
			(layer "F.SilkS")
		)
		(fp_arc
			(start 7.999984 0)
			(mid -0.332341 7.993016)
			(end -7.972298 -0.66421)
			(stroke
				(width 0.1524)
				(type default)
			)
			(layer "F.SilkS")
		)
		(fp_arc
			(start -5.443982 -5.862066)
			(mid 3.197507 -7.333195)
			(end 7.999984 0)
			(stroke
				(width 0.1524)
				(type default)
			)
			(layer "B.SilkS")
		)
		(fp_arc
			(start 7.999984 0)
			(mid -0.319455 7.993705)
			(end -7.974584 -0.638302)
			(stroke
				(width 0.1524)
				(type default)
			)
			(layer "B.SilkS")
		)
		(fp_circle
			(center 0 0)
			(end 7.999984 0)
			(stroke
				(width 0.1)
				(type default)
			)
			(fill no)
			(layer "B.Fab")
		)
		(fp_circle
			(center 0 0)
			(end 7.999984 0)
			(stroke
				(width 0.1)
				(type default)
			)
			(fill no)
			(layer "F.Fab")
		)
		(pad "" np_thru_hole circle
			(at 0 0)
			(size 4.5212 4.5212)
			(drill 4.5212)
			(layers "*.Cu" "*.Mask")
			(clearance 0.381)
			(thermal_gap 0.381)
		)
		(pad "2" thru_hole circle
			(at 3.6322 0)
			(size 0.762 0.762)
			(drill 0.5588)
			(layers "*.Cu" "*.Mask")
			(remove_unused_layers no)
			(net "GND")
			(clearance 0.1524)
			(thermal_gap 0.1524)
		)
		(pad "3" thru_hole circle
			(at 2.568448 -2.568448)
			(size 0.762 0.762)
			(drill 0.5588)
			(layers "*.Cu" "*.Mask")
			(remove_unused_layers no)
			(net "GND")
			(clearance 0.1524)
			(thermal_gap 0.1524)
		)
		(pad "4" thru_hole circle
			(at 0 -3.6322)
			(size 0.762 0.762)
			(drill 0.5588)
			(layers "*.Cu" "*.Mask")
			(remove_unused_layers no)
			(net "GND")
			(clearance 0.1524)
			(thermal_gap 0.1524)
		)
		(pad "5" thru_hole circle
			(at -2.568448 -2.568448)
			(size 0.762 0.762)
			(drill 0.5588)
			(layers "*.Cu" "*.Mask")
			(remove_unused_layers no)
			(net "GND")
			(clearance 0.1524)
			(thermal_gap 0.1524)
		)
		(pad "6" thru_hole circle
			(at -3.6322 0)
			(size 0.762 0.762)
			(drill 0.5588)
			(layers "*.Cu" "*.Mask")
			(remove_unused_layers no)
			(net "GND")
			(clearance 0.1524)
			(thermal_gap 0.1524)
		)
		(pad "7" thru_hole circle
			(at -2.568448 2.568448)
			(size 0.762 0.762)
			(drill 0.5588)
			(layers "*.Cu" "*.Mask")
			(remove_unused_layers no)
			(net "GND")
			(clearance 0.1524)
			(thermal_gap 0.1524)
		)
		(pad "8" thru_hole circle
			(at 0 3.6322)
			(size 0.762 0.762)
			(drill 0.5588)
			(layers "*.Cu" "*.Mask")
			(remove_unused_layers no)
			(net "GND")
			(clearance 0.1524)
			(thermal_gap 0.1524)
		)
		(pad "9" thru_hole circle
			(at 2.568448 2.568448)
			(size 0.762 0.762)
			(drill 0.5588)
			(layers "*.Cu" "*.Mask")
			(remove_unused_layers no)
			(net "GND")
			(clearance 0.1524)
			(thermal_gap 0.1524)
		)
		(zone
			(layer "F.Cu")
			(hatch none 0.5)
			(connect_pads
				(clearance 0)
			)
			(min_thickness 0.25)
			(keepout
				(tracks not_allowed)
				(vias allowed)
				(pads allowed)
				(copperpour not_allowed)
				(footprints allowed)
			)
			(placement
				(enabled no)
				(sheetname "")
			)
			(fill
				(thermal_gap 0.5)
				(thermal_bridge_width 0.5)
				(island_removal_mode 0)
			)
			(polygon
				(pts
					(arc
						(start 321.84975 -262.899906)
						(mid 313.849766 -270.89989)
						(end 321.84975 -278.899874)
					)
					(arc
						(start 321.84975 -275.64969)
						(mid 317.09995 -270.89989)
						(end 321.84975 -266.15009)
					)
				)
			)
		)
		(zone
			(layer "F.Cu")
			(hatch none 0.5)
			(connect_pads
				(clearance 0)
			)
			(min_thickness 0.25)
			(keepout
				(tracks not_allowed)
				(vias allowed)
				(pads allowed)
				(copperpour not_allowed)
				(footprints allowed)
			)
			(placement
				(enabled no)
				(sheetname "")
			)
			(fill
				(thermal_gap 0.5)
				(thermal_bridge_width 0.5)
				(island_removal_mode 0)
			)
			(polygon
				(pts
					(arc
						(start 321.84975 -262.899906)
						(mid 329.849734 -270.89989)
						(end 321.84975 -278.899874)
					)
					(arc
						(start 321.84975 -275.64969)
						(mid 326.59955 -270.89989)
						(end 321.84975 -266.15009)
					)
				)
			)
		)
		(zone
			(layers "F.Cu" "B.Cu" "In1.Cu" "In2.Cu" "In3.Cu" "In4.Cu" "In5.Cu" "In6.Cu"
				"In7.Cu" "In8.Cu" "In9.Cu" "In10.Cu" "In11.Cu" "In12.Cu" "In13.Cu" "In14.Cu"
				"In15.Cu" "In16.Cu"
			)
			(hatch none 0.5)
			(connect_pads
				(clearance 0)
			)
			(min_thickness 0.25)
			(keepout
				(tracks not_allowed)
				(vias allowed)
				(pads allowed)
				(copperpour not_allowed)
				(footprints allowed)
			)
			(placement
				(enabled no)
				(sheetname "")
			)
			(fill
				(thermal_gap 0.5)
				(thermal_bridge_width 0.5)
				(island_removal_mode 0)
			)
			(polygon
				(pts
					(arc
						(start 324.61581 -270.89989)
						(mid 319.08369 -270.89989)
						(end 324.61581 -270.89989)
					)
				)
			)
		)
		(zone
			(layer "B.Cu")
			(hatch none 0.5)
			(connect_pads
				(clearance 0)
			)
			(min_thickness 0.25)
			(keepout
				(tracks not_allowed)
				(vias allowed)
				(pads allowed)
				(copperpour not_allowed)
				(footprints allowed)
			)
			(placement
				(enabled no)
				(sheetname "")
			)
			(fill
				(thermal_gap 0.5)
				(thermal_bridge_width 0.5)
				(island_removal_mode 0)
			)
			(polygon
				(pts
					(arc
						(start 321.84975 -265.89609)
						(mid 316.84595 -270.89989)
						(end 321.84975 -275.90369)
					)
					(arc
						(start 321.84975 -275.42109)
						(mid 317.32855 -270.89989)
						(end 321.84975 -266.37869)
					)
				)
			)
		)
		(zone
			(layer "B.Cu")
			(hatch none 0.5)
			(connect_pads
				(clearance 0)
			)
			(min_thickness 0.25)
			(keepout
				(tracks not_allowed)
				(vias allowed)
				(pads allowed)
				(copperpour not_allowed)
				(footprints allowed)
			)
			(placement
				(enabled no)
				(sheetname "")
			)
			(fill
				(thermal_gap 0.5)
				(thermal_bridge_width 0.5)
				(island_removal_mode 0)
			)
			(polygon
				(pts
					(arc
						(start 321.84975 -265.89609)
						(mid 326.85355 -270.89989)
						(end 321.84975 -275.90369)
					)
					(arc
						(start 321.84975 -275.42109)
						(mid 326.37095 -270.89989)
						(end 321.84975 -266.37869)
					)
				)
			)
		)
	)
	(footprint ""
		(layer "F.Cu")
		(at 304.859436 -61.612526)
		(property "Reference" "PD48"
			(at -3.7084 -2.733548 0)
			(unlocked yes)
			(layer "F.SilkS")
			(effects
				(font
					(size 0.7874 0.5842)
					(thickness 0.1524)
				)
				(justify left)
			)
		)
		(property "Value" ""
			(at 0 0 0)
			(layer "F.Fab")
			(effects
				(font
					(size 1.27 1.27)
				)
			)
		)
		(duplicate_pad_numbers_are_jumpers no)
		(fp_line
			(start -3.656584 -1.970024)
			(end -3.656584 1.970024)
			(stroke
				(width 0.1524)
				(type default)
			)
			(layer "F.SilkS")
		)
		(fp_line
			(start -3.656584 1.970024)
			(end 4.240784 1.970024)
			(stroke
				(width 0.1524)
				(type default)
			)
			(layer "F.SilkS")
		)
		(fp_line
			(start 4.240784 -1.970024)
			(end -3.656584 -1.970024)
			(stroke
				(width 0.1524)
				(type default)
			)
			(layer "F.SilkS")
		)
		(fp_line
			(start 4.240784 1.970024)
			(end 4.240784 -1.970024)
			(stroke
				(width 0.1524)
				(type default)
			)
			(layer "F.SilkS")
		)
		(fp_poly
			(pts
				(xy 3.580384 1.970024) (xy 3.580384 -1.970024) (xy 4.240784 -1.970024) (xy 4.240784 1.970024)
			)
			(stroke
				(width 0)
				(type default)
			)
			(fill yes)
			(layer "F.SilkS")
		)
		(fp_line
			(start -2.3749 -1.970024)
			(end -2.3749 1.970024)
			(stroke
				(width 0.1)
				(type default)
			)
			(layer "F.Fab")
		)
		(fp_line
			(start -2.3749 1.970024)
			(end 2.3749 1.970024)
			(stroke
				(width 0.1)
				(type default)
			)
			(layer "F.Fab")
		)
		(fp_line
			(start 2.3749 -1.970024)
			(end -2.3749 -1.970024)
			(stroke
				(width 0.1)
				(type default)
			)
			(layer "F.Fab")
		)
		(fp_line
			(start 2.3749 1.970024)
			(end 2.3749 -1.970024)
			(stroke
				(width 0.1)
				(type default)
			)
			(layer "F.Fab")
		)
		(fp_text user "+"
			(at -4.9784 -0.23495 0)
			(unlocked yes)
			(layer "F.Fab")
			(effects
				(font
					(size 1.905 1.4224)
					(thickness 0.1524)
				)
				(justify left)
			)
		)
		(fp_text user "-"
			(at 4.1656 -0.23495 0)
			(unlocked yes)
			(layer "F.Fab")
			(effects
				(font
					(size 1.905 1.4224)
					(thickness 0.1524)
				)
				(justify left)
			)
		)
		(pad "A" smd rect
			(at -2.450084 0)
			(size 2.159 2.2606)
			(layers "F.Cu" "F.Mask" "F.Paste")
			(net "GND")
		)
		(pad "C" smd rect
			(at 2.450084 0)
			(size 2.159 2.2606)
			(layers "F.Cu" "F.Mask" "F.Paste")
			(net "P12V_AUX")
		)
	)
)
